# T6G (Grand Teton) — schematic netlist excerpt (pin names and nets, part order shuffled) for the footprints in the layout excerpt that follows; sources: Cadence DE-HDL packaged netlist, KiCad conversion of 04192023_DAF0TMB3IC0_F0TG_MB_C_brd_V02_OCP.brd

J21  SCONN288_DDR506112002KQ  IO  pkg DDR288S_1-1VXC  page 90
  VIN_BULK0  = P12V_MEM_CPU0
  RFU0  = NC
  VIN_MGMT  = P3V3_AUX
  HSCL  = I3C_SPD_DDRE_CPU0_SCL
  HSDA  = I3C_SPD_DDRE_CPU0_SDA
  VSS0  = GND
  DQ0_A  = M_E_CPU0_SA_DQ<0>
  VSS1  = GND
  DQ1_A  = M_E_CPU0_SA_DQ<1>
  VSS2  = GND
  DQS0_A_T  = M_E_CPU0_SA_DQS_DP<0>
  DQS0_A_C  = M_E_CPU0_SA_DQS_DN<0>
  VSS3  = GND
  DQ4_A  = M_E_CPU0_SA_DQ<4>
  VSS4  = GND
  DQ5_A  = M_E_CPU0_SA_DQ<5>
  VSS5  = GND
  DQ8_A  = M_E_CPU0_SA_DQ<8>
  VSS6  = GND
  DQ9_A  = M_E_CPU0_SA_DQ<9>
  VSS7  = GND
  DQS1_A_T  = M_E_CPU0_SA_DQS_DP<1>
  DQS1_A_C  = M_E_CPU0_SA_DQS_DN<1>
  VSS8  = GND
  DQ12_A  = M_E_CPU0_SA_DQ<12>
  VSS9  = GND
  DQ13_A  = M_E_CPU0_SA_DQ<13>
  VSS10  = GND
  DQ16_A  = M_E_CPU0_SA_DQ<16>
  VSS11  = GND
  DQ17_A  = M_E_CPU0_SA_DQ<17>
  VSS12  = GND
  DQS2_A_T  = M_E_CPU0_SA_DQS_DP<2>
  DQS2_A_C  = M_E_CPU0_SA_DQS_DN<2>
  VSS13  = GND
  DQ20_A  = M_E_CPU0_SA_DQ<20>
  VSS14  = GND
  DQ21_A  = M_E_CPU0_SA_DQ<21>
  VSS15  = GND
  DQ24_A  = M_E_CPU0_SA_DQ<24>
  VSS16  = GND
  DQ25_A  = M_E_CPU0_SA_DQ<25>
  VSS17  = GND
  DQS3_A_T  = M_E_CPU0_SA_DQS_DP<3>
  DQS3_A_C  = M_E_CPU0_SA_DQS_DN<3>
  VSS18  = GND
  DQ28_A  = M_E_CPU0_SA_DQ<28>
  VSS19  = GND
  DQ29_A  = M_E_CPU0_SA_DQ<29>
  VSS20  = GND
  CB0_A  = M_E_CPU0_SA_CB<0>
  VSS21  = GND
  CB1_A  = M_E_CPU0_SA_CB<1>
  VSS22  = GND
  DQS4_A_T  = M_E_CPU0_SA_DQS_DP<4>
  DQS4_A_C  = M_E_CPU0_SA_DQS_DN<4>
  VSS23  = GND
  CB4_A  = M_E_CPU0_SA_CB<4>
  VSS24  = GND
  CB5_A  = M_E_CPU0_SA_CB<5>
  VSS25  = GND
  ALERT_N  = M_E_CPU0_ALERT_N
  VSS26  = GND
  CS0_A_N  = M_E_CPU0_SA_CS_N<0>
  VSS27  = GND
  CA0_A  = M_E_CPU0_SA_CA<0>
  VSS28  = GND
  CA2_A  = M_E_CPU0_SA_CA<2>
  VSS29  = GND
  CA4_A  = M_E_CPU0_SA_CA<4>
  VSS30  = GND
  CA6_A  = M_E_CPU0_SA_CA<6>
  VSS31  = GND
  PAR_A  = M_E_CPU0_SA_PAR
  VSS32  = GND
  CA0_B  = M_E_CPU0_SB_CA<0>
  VSS33  = GND
  CA2_B  = M_E_CPU0_SB_CA<2>
  VSS34  = GND
  CA4_B  = M_E_CPU0_SB_CA<4>
  VSS35  = GND
  CA6_B  = M_E_CPU0_SB_CA<6>
  VSS36  = GND
  CS0_B_N  = M_E_CPU0_SB_CS_N<0>
  VSS37  = GND
  \lbd||rsp_a_n\  = M_E_CPU0_SA_RSP<0>
  \lbs||rsp_b_n\  = M_E_CPU0_SB_RSP<0>
  VSS38  = GND
  CB4_B  = M_E_CPU0_SB_CB<4>
  VSS39  = GND
  CB5_B  = M_E_CPU0_SB_CB<5>
  VSS40  = GND
  \dqs9_b_t||tdqs9_b_t||dbi4_b_n\  = M_E_CPU0_SB_DQS_DP<9>
  \dqs9_b_c||tdqs9_b_c\  = M_E_CPU0_SB_DQS_DN<9>
  VSS41  = GND
  CB0_B  = M_E_CPU0_SB_CB<0>
  VSS42  = GND
  CB1_B  = M_E_CPU0_SB_CB<1>
  VSS43  = GND
  DQ0_B  = M_E_CPU0_SB_DQ<0>
  VSS44  = GND
  DQ1_B  = M_E_CPU0_SB_DQ<1>
  VSS45  = GND
  DQS0_B_T  = M_E_CPU0_SB_DQS_DP<0>
  DQS0_B_C  = M_E_CPU0_SB_DQS_DN<0>
  VSS46  = GND
  DQ4_B  = M_E_CPU0_SB_DQ<4>
  VSS47  = GND
  DQ5_B  = M_E_CPU0_SB_DQ<5>
  VSS48  = GND
  DQ8_B  = M_E_CPU0_SB_DQ<8>
  VSS49  = GND
  DQ9_B  = M_E_CPU0_SB_DQ<9>
  VSS50  = GND
  DQS1_B_T  = M_E_CPU0_SB_DQS_DP<1>
  DQS1_B_C  = M_E_CPU0_SB_DQS_DN<1>
  VSS51  = GND
  DQ12_B  = M_E_CPU0_SB_DQ<12>
  VSS52  = GND
  DQ13_B  = M_E_CPU0_SB_DQ<13>
  VSS53  = GND
  DQ16_B  = M_E_CPU0_SB_DQ<16>
  VSS54  = GND
  DQ17_B  = M_E_CPU0_SB_DQ<17>
  VSS55  = GND
  DQS2_B_T  = M_E_CPU0_SB_DQS_DP<2>
  DQS2_B_C  = M_E_CPU0_SB_DQS_DN<2>
  VSS56  = GND
  DQ20_B  = M_E_CPU0_SB_DQ<20>
  VSS57  = GND
  DQ21_B  = M_E_CPU0_SB_DQ<21>
  VSS58  = GND
  DQ24_B  = M_E_CPU0_SB_DQ<24>
  VSS59  = GND
  DQ25_B  = M_E_CPU0_SB_DQ<25>
  VSS60  = GND
  DQS3_B_T  = M_E_CPU0_SB_DQS_DP<3>
  DQS3_B_C  = M_E_CPU0_SB_DQS_DN<3>
  VSS61  = GND
  DQ28_B  = M_E_CPU0_SB_DQ<28>
  VSS62  = GND
  DQ29_B  = M_E_CPU0_SB_DQ<29>
  VSS63  = GND
  RFU1  = NC
  VIN_BULK1  = P12V_MEM_CPU0
  VIN_BULK2  = P12V_MEM_CPU0
  \pwr_good||fail_n\  = PWRGD_CHE_CPU0_DIMM
  HAS  = PD_CHE_CPU0_DIMM_SAA
  RFU2  = NC
  RFU3  = NC
  VSS64  = GND
  DQ2_A  = M_E_CPU0_SA_DQ<2>
  VSS65  = GND
  DQ3_A  = M_E_CPU0_SA_DQ<3>
  VSS66  = GND
  \dqs5_a_c||tdqs5_a_c||dqs5_a_t||tdqs5_a_t\  = M_E_CPU0_SA_DQS_DN<5>
  \dqs5_a_t||tdqs5_a_t\  = M_E_CPU0_SA_DQS_DP<5>
  VSS67  = GND
  DQ6_A  = M_E_CPU0_SA_DQ<6>
  VSS68  = GND
  DQ7_A  = M_E_CPU0_SA_DQ<7>
  VSS69  = GND
  DQ10_A  = M_E_CPU0_SA_DQ<10>
  VSS70  = GND
  DQ11_A  = M_E_CPU0_SA_DQ<11>
  VSS71  = GND
  \dqs6_a_c||tdqs6_a_c||dqs6_a_t||tdqs6_a_t\  = M_E_CPU0_SA_DQS_DN<6>
  \dqs6_a_t||tdqs6_a_t\  = M_E_CPU0_SA_DQS_DP<6>
  VSS72  = GND
  DQ14_A  = M_E_CPU0_SA_DQ<14>
  VSS73  = GND
  DQ15_A  = M_E_CPU0_SA_DQ<15>
  VSS74  = GND
  DQ18_A  = M_E_CPU0_SA_DQ<18>
  VSS75  = GND
  DQ19_A  = M_E_CPU0_SA_DQ<19>
  VSS76  = GND
  \dqs7_a_c||tdqs7_a_c\  = M_E_CPU0_SA_DQS_DN<7>
  \dqs7_a_t||tdqs7_a_t\  = M_E_CPU0_SA_DQS_DP<7>
  VSS77  = GND
  DQ22_A  = M_E_CPU0_SA_DQ<22>
  VSS78  = GND
  DQ23_A  = M_E_CPU0_SA_DQ<23>
  VSS79  = GND
  DQ26_A  = M_E_CPU0_SA_DQ<26>
  VSS80  = GND
  DQ27_A  = M_E_CPU0_SA_DQ<27>
  VSS81  = GND
  \dqs8_a_c||tdqs8_a_c\  = M_E_CPU0_SA_DQS_DN<8>
  \dqs8_a_t||tdqs8_a_t\  = M_E_CPU0_SA_DQS_DP<8>
  VSS82  = GND
  DQ30_A  = M_E_CPU0_SA_DQ<30>
  VSS83  = GND
  DQ31_A  = M_E_CPU0_SA_DQ<31>
  VSS84  = GND
  CB2_A  = M_E_CPU0_SA_CB<2>
  VSS85  = GND
  CB3_A  = M_E_CPU0_SA_CB<3>
  VSS86  = GND
  \dqs9_a_c||tdqs9_a_c\  = M_E_CPU0_SA_DQS_DN<9>
  \dqs9_a_t||tdqs9_a_t\  = M_E_CPU0_SA_DQS_DP<9>
  VSS87  = GND
  CB6_A  = M_E_CPU0_SA_CB<6>
  VSS88  = GND
  CB7_A  = M_E_CPU0_SA_CB<7>
  VSS89  = GND
  RESET_N  = M_E_CPU0_RESET_N
  VSS90  = GND
  CS1_A_N  = M_E_CPU0_SA_CS_N<1>
  VSS91  = GND
  CA1_A  = M_E_CPU0_SA_CA<1>
  VSS92  = GND
  CA3_A  = M_E_CPU0_SA_CA<3>
  VSS93  = GND
  CA5_A  = M_E_CPU0_SA_CA<5>
  VSS94  = GND
  CK_T  = M_E_CPU0_CLK_DP<0>
  CK_C  = M_E_CPU0_CLK_DN<0>
  VSS95  = GND
  RFU4  = NC
  CA1_B  = M_E_CPU0_SB_CA<1>
  VSS96  = GND
  CA3_B  = M_E_CPU0_SB_CA<3>
  VSS97  = GND
  CA5_B  = M_E_CPU0_SB_CA<5>
  VSS98  = GND
  PAR_B  = M_E_CPU0_SB_PAR
  VSS99  = GND
  CS1_B_N  = M_E_CPU0_SB_CS_N<1>
  VSS100  = GND
  RFU5  = NC
  RFU6  = NC
  VSS101  = GND
  CB6_B  = M_E_CPU0_SB_CB<6>
  VSS102  = GND
  CB7_B  = M_E_CPU0_SB_CB<7>
  VSS103  = GND
  DQS4_B_C  = M_E_CPU0_SB_DQS_DN<4>
  DQS4_B_T  = M_E_CPU0_SB_DQS_DP<4>
  VSS104  = GND
  CB2_B  = M_E_CPU0_SB_CB<2>
  VSS105  = GND
  CB3_B  = M_E_CPU0_SB_CB<3>
  VSS106  = GND
  DQ2_B  = M_E_CPU0_SB_DQ<2>
  VSS107  = GND
  DQ3_B  = M_E_CPU0_SB_DQ<3>
  VSS108  = GND
  \dqs5_b_c||tdqs5_b_c\  = M_E_CPU0_SB_DQS_DN<5>
  \dqs5_b_t||tdqs5_b_t\  = M_E_CPU0_SB_DQS_DP<5>
  VSS109  = GND
  DQ6_B  = M_E_CPU0_SB_DQ<6>
  VSS110  = GND
  DQ7_B  = M_E_CPU0_SB_DQ<7>
  VSS111  = GND
  DQ10_B  = M_E_CPU0_SB_DQ<10>
  VSS112  = GND
  DQ11_B  = M_E_CPU0_SB_DQ<11>
  VSS113  = GND
  \dqs6_b_c||tdqs6_b_c\  = M_E_CPU0_SB_DQS_DN<6>
  \dqs6_b_t||tdqs6_b_t\  = M_E_CPU0_SB_DQS_DP<6>
  VSS114  = GND
  DQ14_B  = M_E_CPU0_SB_DQ<14>
  VSS115  = GND
  DQ15_B  = M_E_CPU0_SB_DQ<15>
  VSS116  = GND
  DQ18_B  = M_E_CPU0_SB_DQ<18>
  VSS117  = GND
  DQ19_B  = M_E_CPU0_SB_DQ<19>
  VSS118  = GND
  \dqs7_b_c||tdqs7_b_c\  = M_E_CPU0_SB_DQS_DN<7>
  \dqs7_b_t||tdqs7_b_t\  = M_E_CPU0_SB_DQS_DP<7>
  VSS119  = GND
  DQ22_B  = M_E_CPU0_SB_DQ<22>
  VSS120  = GND
  DQ23_B  = M_E_CPU0_SB_DQ<23>
  VSS121  = GND
  DQ26_B  = M_E_CPU0_SB_DQ<26>
  VSS122  = GND
  DQ27_B  = M_E_CPU0_SB_DQ<27>
  VSS123  = GND
  \dqs8_b_c||tdqs8_b_c\  = M_E_CPU0_SB_DQS_DN<8>
  \dqs8_b_t||tdqs8_b_t\  = M_E_CPU0_SB_DQS_DP<8>
  VSS124  = GND
  DQ30_B  = M_E_CPU0_SB_DQ<30>
  VSS125  = GND
  DQ31_B  = M_E_CPU0_SB_DQ<31>
  VSS126  = GND
  G1  = GND
  G2  = GND
  G3  = GND

(kicad_pcb
	(version 20260206)
	(generator "pcbnew")
	(generator_version "10.0")
	(general
		(thickness 1.6)
		(legacy_teardrops no)
	)
	(paper "A4")
	(title_block
		(title "04192023_DAF0TMB3IC0_F0TG_MB_C_brd_V02_OCP.brd")
		(comment 1 "Grand Teton / footprint 3 of 8354 (J21), pads 47-92 of 291")
	)
	(layers
		(0 "F.Cu" signal "TOP")
		(4 "In1.Cu" signal "GND")
		(6 "In2.Cu" signal "IN1")
		(8 "In3.Cu" signal "GND1")
		(10 "In4.Cu" signal "IN2")
		(12 "In5.Cu" signal "GND2")
		(14 "In6.Cu" signal "IN3")
		(16 "In7.Cu" signal "GND3")
		(18 "In8.Cu" signal "VCC")
		(20 "In9.Cu" signal "VCC1")
		(22 "In10.Cu" signal "GND4")
		(24 "In11.Cu" signal "IN4")
		(26 "In12.Cu" signal "GND5")
		(28 "In13.Cu" signal "IN5")
		(30 "In14.Cu" signal "GND6")
		(32 "In15.Cu" signal "IN6")
		(34 "In16.Cu" signal "GND7")
		(2 "B.Cu" signal "BOTTOM")
		(9 "F.Adhes" user "F.Adhesive")
		(11 "B.Adhes" user "B.Adhesive")
		(13 "F.Paste" user "Package Geometry/Pastemask Top")
		(15 "B.Paste" user "Package Geometry/Pastemask Bottom")
		(5 "F.SilkS" user "Ref Des/Silkscreen Top")
		(7 "B.SilkS" user "Ref Des/Silkscreen Bottom")
		(1 "F.Mask" user "Board Geometry/Soldermask Top")
		(3 "B.Mask" user "Board Geometry/Soldermask Bottom")
		(17 "Dwgs.User" user "User.Drawings")
		(19 "Cmts.User" user "User.Comments")
		(21 "Eco1.User" user "User.Eco1")
		(23 "Eco2.User" user "User.Eco2")
		(25 "Edge.Cuts" user "Board Geometry/Outline")
		(27 "Margin" user)
		(31 "F.CrtYd" user "Package Geometry/Place Bound Top")
		(29 "B.CrtYd" user "Package Geometry/Place Bound Bottom")
		(35 "F.Fab" user "Ref Des/Assembly Top")
		(33 "B.Fab" user "Ref Des/Assembly Bottom")
	)
	(footprint ""
		(layer "F.Cu")
		(at 275.142198 -255.560068 180)
		(property "Reference" "J21"
			(at -2.2098 -81.984088 0)
			(unlocked yes)
			(layer "F.SilkS")
			(effects
				(font
					(size 0.7874 0.5842)
					(thickness 0.1524)
				)
			)
		)
		(property "Value" ""
			(at 0 0 180)
			(layer "F.Fab")
			(effects
				(font
					(size 1.27 1.27)
				)
			)
		)
		(duplicate_pad_numbers_are_jumpers no)
		(pad "47" smd rect
			(at -2.050034 -24.224996 90)
			(size 0.519938 1.4986)
			(layers "F.Cu" "F.Mask" "F.Paste")
			(net "M_E_CPU0_SA_DQ<28>")
		)
		(pad "48" smd rect
			(at -2.050034 -23.375112 90)
			(size 0.519938 1.4986)
			(layers "F.Cu" "F.Mask" "F.Paste")
			(net "GND")
		)
		(pad "49" smd rect
			(at -2.050034 -22.524974 90)
			(size 0.519938 1.4986)
			(layers "F.Cu" "F.Mask" "F.Paste")
			(net "M_E_CPU0_SA_DQ<29>")
		)
		(pad "50" smd rect
			(at -2.050034 -21.67509 90)
			(size 0.519938 1.4986)
			(layers "F.Cu" "F.Mask" "F.Paste")
			(net "GND")
		)
		(pad "51" smd rect
			(at -2.050034 -20.824952 90)
			(size 0.519938 1.4986)
			(layers "F.Cu" "F.Mask" "F.Paste")
			(net "M_E_CPU0_SA_CB<0>")
		)
		(pad "52" smd rect
			(at -2.050034 -19.975068 90)
			(size 0.519938 1.4986)
			(layers "F.Cu" "F.Mask" "F.Paste")
			(net "GND")
		)
		(pad "53" smd rect
			(at -2.050034 -19.12493 90)
			(size 0.519938 1.4986)
			(layers "F.Cu" "F.Mask" "F.Paste")
			(net "M_E_CPU0_SA_CB<1>")
		)
		(pad "54" smd rect
			(at -2.050034 -18.275046 90)
			(size 0.519938 1.4986)
			(layers "F.Cu" "F.Mask" "F.Paste")
			(net "GND")
		)
		(pad "55" smd rect
			(at -2.050034 -17.424908 90)
			(size 0.519938 1.4986)
			(layers "F.Cu" "F.Mask" "F.Paste")
			(net "M_E_CPU0_SA_DQS_DP<4>")
		)
		(pad "56" smd rect
			(at -2.050034 -16.575024 90)
			(size 0.519938 1.4986)
			(layers "F.Cu" "F.Mask" "F.Paste")
			(net "M_E_CPU0_SA_DQS_DN<4>")
		)
		(pad "57" smd rect
			(at -2.050034 -15.724886 90)
			(size 0.519938 1.4986)
			(layers "F.Cu" "F.Mask" "F.Paste")
			(net "GND")
		)
		(pad "58" smd rect
			(at -2.050034 -14.875002 90)
			(size 0.519938 1.4986)
			(layers "F.Cu" "F.Mask" "F.Paste")
			(net "M_E_CPU0_SA_CB<4>")
		)
		(pad "59" smd rect
			(at -2.050034 -14.025118 90)
			(size 0.519938 1.4986)
			(layers "F.Cu" "F.Mask" "F.Paste")
			(net "GND")
		)
		(pad "60" smd rect
			(at -2.050034 -13.17498 90)
			(size 0.519938 1.4986)
			(layers "F.Cu" "F.Mask" "F.Paste")
			(net "M_E_CPU0_SA_CB<5>")
		)
		(pad "61" smd rect
			(at -2.050034 -12.325096 90)
			(size 0.519938 1.4986)
			(layers "F.Cu" "F.Mask" "F.Paste")
			(net "GND")
		)
		(pad "62" smd rect
			(at -2.050034 -11.474958 90)
			(size 0.519938 1.4986)
			(layers "F.Cu" "F.Mask" "F.Paste")
			(net "M_E_CPU0_ALERT_N")
		)
		(pad "63" smd rect
			(at -2.050034 -10.625074 90)
			(size 0.519938 1.4986)
			(layers "F.Cu" "F.Mask" "F.Paste")
			(net "GND")
		)
		(pad "64" smd rect
			(at -2.050034 -9.774936 90)
			(size 0.519938 1.4986)
			(layers "F.Cu" "F.Mask" "F.Paste")
			(net "M_E_CPU0_SA_CS_N<0>")
		)
		(pad "65" smd rect
			(at -2.050034 -8.925052 90)
			(size 0.519938 1.4986)
			(layers "F.Cu" "F.Mask" "F.Paste")
			(net "GND")
		)
		(pad "66" smd rect
			(at -2.050034 -8.074914 90)
			(size 0.519938 1.4986)
			(layers "F.Cu" "F.Mask" "F.Paste")
			(net "M_E_CPU0_SA_CA<0>")
		)
		(pad "67" smd rect
			(at -2.050034 -7.22503 90)
			(size 0.519938 1.4986)
			(layers "F.Cu" "F.Mask" "F.Paste")
			(net "GND")
		)
		(pad "68" smd rect
			(at -2.050034 -6.374892 90)
			(size 0.519938 1.4986)
			(layers "F.Cu" "F.Mask" "F.Paste")
			(net "M_E_CPU0_SA_CA<2>")
		)
		(pad "69" smd rect
			(at -2.050034 -5.525008 90)
			(size 0.519938 1.4986)
			(layers "F.Cu" "F.Mask" "F.Paste")
			(net "GND")
		)
		(pad "70" smd rect
			(at -2.050034 -4.675124 90)
			(size 0.519938 1.4986)
			(layers "F.Cu" "F.Mask" "F.Paste")
			(net "M_E_CPU0_SA_CA<4>")
		)
		(pad "71" smd rect
			(at -2.050034 -3.824986 90)
			(size 0.519938 1.4986)
			(layers "F.Cu" "F.Mask" "F.Paste")
			(net "GND")
		)
		(pad "72" smd rect
			(at -2.050034 -2.975102 90)
			(size 0.519938 1.4986)
			(layers "F.Cu" "F.Mask" "F.Paste")
			(net "M_E_CPU0_SA_CA<6>")
		)
		(pad "73" smd rect
			(at -2.050034 -2.124964 90)
			(size 0.519938 1.4986)
			(layers "F.Cu" "F.Mask" "F.Paste")
			(net "GND")
		)
		(pad "74" smd rect
			(at -2.050034 -1.27508 90)
			(size 0.519938 1.4986)
			(layers "F.Cu" "F.Mask" "F.Paste")
			(net "M_E_CPU0_SA_PAR")
		)
		(pad "75" smd rect
			(at -2.050034 -0.424942 90)
			(size 0.519938 1.4986)
			(layers "F.Cu" "F.Mask" "F.Paste")
			(net "GND")
		)
		(pad "76" smd rect
			(at -2.050034 5.525008 90)
			(size 0.519938 1.4986)
			(layers "F.Cu" "F.Mask" "F.Paste")
			(net "M_E_CPU0_SB_CA<0>")
		)
		(pad "77" smd rect
			(at -2.050034 6.374892 90)
			(size 0.519938 1.4986)
			(layers "F.Cu" "F.Mask" "F.Paste")
			(net "GND")
		)
		(pad "78" smd rect
			(at -2.050034 7.22503 90)
			(size 0.519938 1.4986)
			(layers "F.Cu" "F.Mask" "F.Paste")
			(net "M_E_CPU0_SB_CA<2>")
		)
		(pad "79" smd rect
			(at -2.050034 8.074914 90)
			(size 0.519938 1.4986)
			(layers "F.Cu" "F.Mask" "F.Paste")
			(net "GND")
		)
		(pad "80" smd rect
			(at -2.050034 8.925052 90)
			(size 0.519938 1.4986)
			(layers "F.Cu" "F.Mask" "F.Paste")
			(net "M_E_CPU0_SB_CA<4>")
		)
		(pad "81" smd rect
			(at -2.050034 9.774936 90)
			(size 0.519938 1.4986)
			(layers "F.Cu" "F.Mask" "F.Paste")
			(net "GND")
		)
		(pad "82" smd rect
			(at -2.050034 10.625074 90)
			(size 0.519938 1.4986)
			(layers "F.Cu" "F.Mask" "F.Paste")
			(net "M_E_CPU0_SB_CA<6>")
		)
		(pad "83" smd rect
			(at -2.050034 11.474958 90)
			(size 0.519938 1.4986)
			(layers "F.Cu" "F.Mask" "F.Paste")
			(net "GND")
		)
		(pad "84" smd rect
			(at -2.050034 12.325096 90)
			(size 0.519938 1.4986)
			(layers "F.Cu" "F.Mask" "F.Paste")
			(net "M_E_CPU0_SB_CS_N<0>")
		)
		(pad "85" smd rect
			(at -2.050034 13.17498 90)
			(size 0.519938 1.4986)
			(layers "F.Cu" "F.Mask" "F.Paste")
			(net "GND")
		)
		(pad "86" smd rect
			(at -2.050034 14.025118 90)
			(size 0.519938 1.4986)
			(layers "F.Cu" "F.Mask" "F.Paste")
			(net "M_E_CPU0_SA_RSP<0>")
		)
		(pad "87" smd rect
			(at -2.050034 14.875002 90)
			(size 0.519938 1.4986)
			(layers "F.Cu" "F.Mask" "F.Paste")
			(net "M_E_CPU0_SB_RSP<0>")
		)
		(pad "88" smd rect
			(at -2.050034 15.724886 90)
			(size 0.519938 1.4986)
			(layers "F.Cu" "F.Mask" "F.Paste")
			(net "GND")
		)
		(pad "89" smd rect
			(at -2.050034 16.575024 90)
			(size 0.519938 1.4986)
			(layers "F.Cu" "F.Mask" "F.Paste")
			(net "M_E_CPU0_SB_CB<4>")
		)
		(pad "90" smd rect
			(at -2.050034 17.424908 90)
			(size 0.519938 1.4986)
			(layers "F.Cu" "F.Mask" "F.Paste")
			(net "GND")
		)
		(pad "91" smd rect
			(at -2.050034 18.275046 90)
			(size 0.519938 1.4986)
			(layers "F.Cu" "F.Mask" "F.Paste")
			(net "M_E_CPU0_SB_CB<5>")
		)
		(pad "92" smd rect
			(at -2.050034 19.12493 90)
			(size 0.519938 1.4986)
			(layers "F.Cu" "F.Mask" "F.Paste")
			(net "GND")
		)
	)
)
